(kicad_pcb
	(version 20221018)
	(generator pcbnew)
	(general
    (thickness 1.518)
  )
	(paper "A4")
	(title_block
    (title "Kria K26 Devboard")
    (date "2024-03-26")
    (rev "1.2.5")
    (comment 1 "www.antmicro.com")
    (comment 2 "Antmicro Ltd.")
		(comment 9 "footprints 629-637 of 660")
	)
	(layers
    (0 "F.Cu" mixed)
    (1 "In1.Cu" power)
    (2 "In2.Cu" mixed)
    (3 "In3.Cu" power)
    (4 "In4.Cu" mixed)
    (5 "In5.Cu" power)
    (6 "In6.Cu" mixed)
    (31 "B.Cu" power)
    (32 "B.Adhes" user "B.Adhesive")
    (33 "F.Adhes" user "F.Adhesive")
    (34 "B.Paste" user)
    (35 "F.Paste" user)
    (36 "B.SilkS" user "B.Silkscreen")
    (37 "F.SilkS" user "F.Silkscreen")
    (38 "B.Mask" user)
    (39 "F.Mask" user)
    (40 "Dwgs.User" user "User.Drawings")
    (41 "Cmts.User" user "User.Comments")
    (42 "Eco1.User" user "User.Eco1")
    (43 "Eco2.User" user "User.Eco2")
    (44 "Edge.Cuts" user)
    (45 "Margin" user)
    (46 "B.CrtYd" user "B.Courtyard")
    (47 "F.CrtYd" user "F.Courtyard")
    (48 "B.Fab" user)
    (49 "F.Fab" user)
  )
	(footprint "kria-k26-devboard-footprints:C_0603_1608Metric" (layer "B.Cu")
    (at 152 110.25)
    (descr "Capacitor SMD 0603")
    (tags "capacitor 0603")
    (property "Author" "Antmicro")
    (property "Dielectric" "")
    (property "License" "Apache-2.0")
    (property "MPN" "CL10A105KA8NNNC")
    (property "Manufacturer" "Samsung")
    (property "Sheetfile" "debug.kicad_sch")
    (property "Sheetname" "Debug and JTAG")
    (property "Val" "1u/25V")
    (property "Voltage" "")
    (property "ki_description" " ")
    (attr smd)
    (fp_text reference "C155" (at 4 0.43 180) (layer "B.SilkS")
        (effects (font (size 0.7 0.7) (thickness 0.15)) (justify left bottom mirror))
    )
    (fp_text value "C_1u_25V_0603" (at 0 -1.6 180) (layer "B.Fab") hide
        (effects (font (size 0.7 0.7) (thickness 0.15)) (justify left bottom mirror))
    )
    (fp_text user "Author: Antmicro" (at -1.682 -4.894 180) (layer "B.Fab") hide
        (effects (font (size 0.7 0.7) (thickness 0.15)) (justify left bottom mirror))
    )
    (fp_text user "${REFERENCE}" (at -1.682 -3.895 180) (layer "B.Fab") hide
        (effects (font (size 0.7 0.7) (thickness 0.15)) (justify left bottom mirror))
    )
    (fp_text user "License: Apache-2.0" (at -1.682 -5.895 180) (layer "B.Fab") hide
        (effects (font (size 0.7 0.7) (thickness 0.15)) (justify left bottom mirror))
    )
    (fp_line (start -0.3 -0.3) (end 0.3 -0.3)
      (stroke (width 0.15) (type solid)) (layer "B.SilkS"))
    (fp_line (start -0.3 0.3) (end 0.3 0.3)
      (stroke (width 0.15) (type solid)) (layer "B.SilkS"))
    (fp_rect (start -1.24 0.7) (end 1.24 -0.7)
      (stroke (width 0.05) (type solid)) (fill none) (layer "B.CrtYd"))
    (fp_rect (start -0.8 0.4) (end 0.8 -0.4)
      (stroke (width 0.15) (type solid)) (fill none) (layer "B.Fab"))
    (pad "1" smd roundrect (at -0.7 0) (size 0.6 0.8) (layers "B.Cu" "B.Paste" "B.Mask") (roundrect_rratio 0.2)
      (net 313 "/Debug and JTAG/USB_VBUS") (pintype "passive"))
    (pad "2" smd roundrect (at 0.7 0) (size 0.6 0.8) (layers "B.Cu" "B.Paste" "B.Mask") (roundrect_rratio 0.2)
      (net 1 "GND") (pintype "passive"))
  )
	(footprint "kria-k26-devboard-footprints:C_0402_1005Metric" (layer "B.Cu")
    (at 151.85 111.75)
    (descr "Capacitor SMD 0402")
    (tags "capacitor SMD 0402")
    (property "Author" "Antmicro")
    (property "Dielectric" "")
    (property "License" "Apache-2.0")
    (property "MPN" "C1005X6S1A105K050BC")
    (property "Manufacturer" "TDK")
    (property "Sheetfile" "debug.kicad_sch")
    (property "Sheetname" "Debug and JTAG")
    (property "Val" "1u")
    (property "Voltage" "")
    (property "ki_description" " ")
    (attr smd)
    (fp_text reference "C159" (at 3.832 0.35 180) (layer "B.SilkS")
        (effects (font (size 0.7 0.7) (thickness 0.15)) (justify left bottom mirror))
    )
    (fp_text value "C_1u_0402" (at 0 -1.4 180) (layer "B.Fab") hide
        (effects (font (size 0.7 0.7) (thickness 0.15)) (justify left bottom mirror))
    )
    (fp_text user "${REFERENCE}" (at -0.932 -3.168 180) (layer "B.Fab") hide
        (effects (font (size 0.7 0.7) (thickness 0.15)) (justify left bottom mirror))
    )
    (fp_text user "Author: Antmicro" (at -0.932 -4.17 180) (layer "B.Fab") hide
        (effects (font (size 0.7 0.7) (thickness 0.15)) (justify left bottom mirror))
    )
    (fp_text user "License: Apache-2.0" (at -0.932 -5.17 180) (layer "B.Fab") hide
        (effects (font (size 0.7 0.7) (thickness 0.15)) (justify left bottom mirror))
    )
    (fp_rect (start -0.94 0.47) (end 0.94 -0.47)
      (stroke (width 0.05) (type solid)) (fill none) (layer "B.CrtYd"))
    (fp_rect (start -0.499 0.249) (end 0.499 -0.249)
      (stroke (width 0.15) (type solid)) (fill none) (layer "B.Fab"))
    (pad "1" smd roundrect (at -0.484 0) (size 0.59 0.64) (layers "B.Cu" "B.Paste" "B.Mask") (roundrect_rratio 0.25)
      (net 138 "/Debug and JTAG/USB_3V3") (pintype "passive"))
    (pad "2" smd roundrect (at 0.484 0) (size 0.59 0.64) (layers "B.Cu" "B.Paste" "B.Mask") (roundrect_rratio 0.25)
      (net 1 "GND") (pintype "passive"))
  )
	(footprint "kria-k26-devboard-footprints:L_0805_2012Metric" (layer "B.Cu")
    (at 138.4046 83.7946 180)
    (descr "Inductor  SMD 0805")
    (tags "inductor SMD 0805")
    (property "Author" "Antmicro")
    (property "IMax" "")
    (property "ISat" "")
    (property "License" "Apache-2.0")
    (property "MPN" "TFM201208ALD-1R0MTCA")
    (property "Manufacturer" "TDK")
    (property "Sheetfile" "dc-dc-conventers.kicad_sch")
    (property "Sheetname" "DC/DC conventers")
    (property "Size" "1.25x0.8")
    (property "Val" "1u/2.5A")
    (attr smd)
    (fp_text reference "L4" (at -1.0354 -1.7954) (layer "B.SilkS")
        (effects (font (size 0.7 0.7) (thickness 0.15)) (justify left bottom mirror))
    )
    (fp_text value "L_1u_2.5A_0805" (at 0 -1.947) (layer "B.Fab") hide
        (effects (font (size 0.7 0.7) (thickness 0.15)) (justify left bottom mirror))
    )
    (fp_text user "Author: Antmicro" (at -1.9 -5.947) (layer "B.Fab") hide
        (effects (font (size 0.7 0.7) (thickness 0.15)) (justify left bottom mirror))
    )
    (fp_text user "${REFERENCE}" (at -1.9 -3.947) (layer "B.Fab") hide
        (effects (font (size 0.7 0.7) (thickness 0.15)) (justify left bottom mirror))
    )
    (fp_text user "License: Apache-2.0" (at -1.9 -4.947) (layer "B.Fab") hide
        (effects (font (size 0.7 0.7) (thickness 0.15)) (justify left bottom mirror))
    )
    (fp_line (start -0.3 -0.8) (end 0.3 -0.8)
      (stroke (width 0.15) (type solid)) (layer "B.SilkS"))
    (fp_line (start -0.3 0.8) (end 0.3 0.8)
      (stroke (width 0.15) (type solid)) (layer "B.SilkS"))
    (fp_rect (start -1.9 0.93) (end 1.9 -0.93)
      (stroke (width 0.05) (type solid)) (fill none) (layer "B.CrtYd"))
    (fp_rect (start -0.95 0.675) (end 0.95 -0.675)
      (stroke (width 0.15) (type solid)) (fill none) (layer "B.Fab"))
    (pad "1" smd rect (at -1.05 0 180) (size 1.2 1.2) (layers "B.Cu" "B.Paste" "B.Mask")
      (net 310 "/Power Supply/DC/DC conventers/SW_PS_2V5") (pintype "passive"))
    (pad "2" smd rect (at 1.05 0 180) (size 1.2 1.2) (layers "B.Cu" "B.Paste" "B.Mask")
      (net 766 "/Power Supply/DC/DC conventers/PS_2V5_OUT") (pintype "passive"))
  )
	(footprint "kria-k26-devboard-footprints:L_0805_2012Metric" (layer "B.Cu")
    (at 136.54 94.81 -90)
    (descr "Inductor  SMD 0805")
    (tags "inductor SMD 0805")
    (property "Author" "Antmicro")
    (property "IMax" "")
    (property "ISat" "")
    (property "License" "Apache-2.0")
    (property "MPN" "TFM201208ALD-1R0MTCA")
    (property "Manufacturer" "TDK")
    (property "Sheetfile" "dc-dc-conventers.kicad_sch")
    (property "Sheetname" "DC/DC conventers")
    (property "Size" "1.25x0.8")
    (property "Val" "1u/2.5A")
    (attr smd)
    (fp_text reference "L7" (at 1.845 -0.436 90) (layer "B.SilkS")
        (effects (font (size 0.7 0.7) (thickness 0.15)) (justify left bottom mirror))
    )
    (fp_text value "L_1u_2.5A_0805" (at 0 -1.947 90) (layer "B.Fab") hide
        (effects (font (size 0.7 0.7) (thickness 0.15)) (justify left bottom mirror))
    )
    (fp_text user "License: Apache-2.0" (at -1.9 -4.947 90) (layer "B.Fab") hide
        (effects (font (size 0.7 0.7) (thickness 0.15)) (justify left bottom mirror))
    )
    (fp_text user "Author: Antmicro" (at -1.9 -5.947 90) (layer "B.Fab") hide
        (effects (font (size 0.7 0.7) (thickness 0.15)) (justify left bottom mirror))
    )
    (fp_text user "${REFERENCE}" (at -1.9 -3.947 90) (layer "B.Fab") hide
        (effects (font (size 0.7 0.7) (thickness 0.15)) (justify left bottom mirror))
    )
    (fp_line (start -0.3 -0.8) (end 0.3 -0.8)
      (stroke (width 0.15) (type solid)) (layer "B.SilkS"))
    (fp_line (start -0.3 0.8) (end 0.3 0.8)
      (stroke (width 0.15) (type solid)) (layer "B.SilkS"))
    (fp_rect (start -1.9 0.93) (end 1.9 -0.93)
      (stroke (width 0.05) (type solid)) (fill none) (layer "B.CrtYd"))
    (fp_rect (start -0.95 0.675) (end 0.95 -0.675)
      (stroke (width 0.15) (type solid)) (fill none) (layer "B.Fab"))
    (pad "1" smd rect (at -1.05 0 270) (size 1.2 1.2) (layers "B.Cu" "B.Paste" "B.Mask")
      (net 256 "/Power Supply/DC/DC conventers/SW_PS_1V0") (pintype "passive"))
    (pad "2" smd rect (at 1.05 0 270) (size 1.2 1.2) (layers "B.Cu" "B.Paste" "B.Mask")
      (net 769 "/Power Supply/DC/DC conventers/PS_1V0_OUT") (pintype "passive"))
  )
	(footprint "kria-k26-devboard-footprints:SOT-416" (layer "B.Cu")
    (at 138.756 95.849 180)
    (descr "SOT-416")
    (tags "SOT-416")
    (property "Author" "Antmicro")
    (property "License" "Apache-2.0")
    (property "MPN" "DTC014TEBTL")
    (property "Manufacturer" "ROHM Semiconductor")
    (property "Sheetfile" "dc-dc-conventers.kicad_sch")
    (property "Sheetname" "DC/DC conventers")
    (property "ki_description" "Digital NPN Transistor, 10k/NONE, EMT-3")
    (attr smd)
    (fp_text reference "Q14" (at -1.244 -4.761) (layer "B.SilkS")
        (effects (font (size 0.7 0.7) (thickness 0.15)) (justify left bottom mirror))
    )
    (fp_text value "DTC014T_SOT-416" (at 0 -2) (layer "B.Fab") hide
        (effects (font (size 0.7 0.7) (thickness 0.15)) (justify left bottom mirror))
    )
    (fp_text user "License: Apache-2.0" (at -1 -5.802) (layer "B.Fab") hide
        (effects (font (size 0.7 0.7) (thickness 0.15)) (justify left bottom mirror))
    )
    (fp_text user "Author: Antmicro" (at -1 -4.602) (layer "B.Fab") hide
        (effects (font (size 0.7 0.7) (thickness 0.15)) (justify left bottom mirror))
    )
    (fp_text user "${REFERENCE}" (at -1 -3.4) (layer "B.Fab") hide
        (effects (font (size 0.7 0.7) (thickness 0.15)) (justify left bottom mirror))
    )
    (fp_line (start -0.5 0.15) (end -0.5 -0.15)
      (stroke (width 0.15) (type solid)) (layer "B.SilkS"))
    (fp_line (start 0.5 -0.9) (end -0.5 -0.9)
      (stroke (width 0.15) (type solid)) (layer "B.SilkS"))
    (fp_line (start 0.5 -0.9) (end 0.5 -0.7)
      (stroke (width 0.15) (type solid)) (layer "B.SilkS"))
    (fp_line (start 0.508 0.9) (end -0.5 0.9)
      (stroke (width 0.15) (type solid)) (layer "B.SilkS"))
    (fp_line (start 0.508 0.9) (end 0.508 0.592)
      (stroke (width 0.15) (type solid)) (layer "B.SilkS"))
    (fp_rect (start -1 1.05) (end 1 -1.05)
      (stroke (width 0.05) (type solid)) (fill none) (layer "B.CrtYd"))
    (fp_line (start -0.05 0.9) (end -0.45 0.5)
      (stroke (width 0.15) (type solid)) (layer "B.Fab"))
    (fp_rect (start 0.45 -0.9) (end -0.45 0.9)
      (stroke (width 0.15) (type solid)) (fill none) (layer "B.Fab"))
    (pad "1" smd rect (at -0.652 0.5 180) (size 0.6 0.5) (layers "B.Cu" "B.Paste" "B.Mask")
      (net 769 "/Power Supply/DC/DC conventers/PS_1V0_OUT") (pinfunction "B") (pintype "input"))
    (pad "2" smd rect (at -0.652 -0.498 180) (size 0.6 0.5) (layers "B.Cu" "B.Paste" "B.Mask")
      (net 1 "GND") (pinfunction "E") (pintype "passive"))
    (pad "3" smd rect (at 0.65 0 180) (size 0.6 0.5) (layers "B.Cu" "B.Paste" "B.Mask")
      (net 339 "Net-(Q14-C)") (pinfunction "C") (pintype "passive"))
  )
	(footprint "kria-k26-devboard-footprints:C_0402_1005Metric" (layer "B.Cu")
    (at 108.95 87.55)
    (descr "Capacitor SMD 0402")
    (tags "capacitor SMD 0402")
    (property "Author" "Antmicro")
    (property "Dielectric" "X5R")
    (property "License" "Apache-2.0")
    (property "MPN" "GRM155R61H104KE14D")
    (property "Manufacturer" "Murata")
    (property "Sheetfile" "k26_som.kicad_sch")
    (property "Sheetname" "Xilinx K26 SOM")
    (property "Val" "100n")
    (property "Voltage" "50V")
    (property "ki_description" " ")
    (attr smd)
    (fp_text reference "C250" (at 3.68 1.56 180) (layer "B.SilkS")
        (effects (font (size 0.7 0.7) (thickness 0.15)) (justify left bottom mirror))
    )
    (fp_text value "C_100n_0402" (at 0 -1.4 180) (layer "B.Fab") hide
        (effects (font (size 0.7 0.7) (thickness 0.15)) (justify left bottom mirror))
    )
    (fp_text user "License: Apache-2.0" (at -0.932 -5.17 180) (layer "B.Fab") hide
        (effects (font (size 0.7 0.7) (thickness 0.15)) (justify left bottom mirror))
    )
    (fp_text user "Author: Antmicro" (at -0.932 -4.17 180) (layer "B.Fab") hide
        (effects (font (size 0.7 0.7) (thickness 0.15)) (justify left bottom mirror))
    )
    (fp_text user "${REFERENCE}" (at -0.932 -3.168 180) (layer "B.Fab") hide
        (effects (font (size 0.7 0.7) (thickness 0.15)) (justify left bottom mirror))
    )
    (fp_rect (start -0.94 0.47) (end 0.94 -0.47)
      (stroke (width 0.05) (type solid)) (fill none) (layer "B.CrtYd"))
    (fp_rect (start -0.499 0.249) (end 0.499 -0.249)
      (stroke (width 0.15) (type solid)) (fill none) (layer "B.Fab"))
    (pad "1" smd roundrect (at -0.484 0) (size 0.59 0.64) (layers "B.Cu" "B.Paste" "B.Mask") (roundrect_rratio 0.25)
      (net 243 "Net-(Q6-D)") (pintype "passive"))
    (pad "2" smd roundrect (at 0.484 0) (size 0.59 0.64) (layers "B.Cu" "B.Paste" "B.Mask") (roundrect_rratio 0.25)
      (net 1 "GND") (pintype "passive"))
  )
	(footprint "kria-k26-devboard-footprints:R_0402_1005Metric" (layer "B.Cu")
    (at 99 87.45 180)
    (descr "Resistor SMD 0402")
    (tags "resistor SMD 0402")
    (property "Author" "Antmicro")
    (property "License" "Apache-2.0")
    (property "MPN" "CR0402-FX-1002GLF")
    (property "Manufacturer" "Bourns")
    (property "Sheetfile" "k26_som.kicad_sch")
    (property "Sheetname" "Xilinx K26 SOM")
    (property "Tolerance" "1%")
    (property "Val" "10k")
    (property "ki_description" "10k resistor in 0402 package with 1% tolerance")
    (attr smd)
    (fp_text reference "R177" (at -0.98 0.63) (layer "B.SilkS")
        (effects (font (size 0.7 0.7) (thickness 0.15)) (justify left bottom mirror))
    )
    (fp_text value "R_10k_0402" (at 0 -1.4) (layer "B.Fab") hide
        (effects (font (size 0.7 0.7) (thickness 0.15)) (justify left bottom mirror))
    )
    (fp_text user "${REFERENCE}" (at -0.95 -3.168) (layer "B.Fab") hide
        (effects (font (size 0.7 0.7) (thickness 0.15)) (justify left bottom mirror))
    )
    (fp_text user "License: Apache-2.0" (at -0.95 -5.169) (layer "B.Fab") hide
        (effects (font (size 0.7 0.7) (thickness 0.15)) (justify left bottom mirror))
    )
    (fp_text user "Author: Antmicro" (at -0.95 -4.169) (layer "B.Fab") hide
        (effects (font (size 0.7 0.7) (thickness 0.15)) (justify left bottom mirror))
    )
    (fp_rect (start -0.93 0.47) (end 0.93 -0.47)
      (stroke (width 0.05) (type solid)) (fill none) (layer "B.CrtYd"))
    (fp_rect (start -0.5 0.25) (end 0.5 -0.25)
      (stroke (width 0.15) (type solid)) (fill none) (layer "B.Fab"))
    (pad "1" smd roundrect (at -0.485 0 180) (size 0.59 0.64) (layers "B.Cu" "B.Paste" "B.Mask") (roundrect_rratio 0.25)
      (net 306 "USB_5V") (pintype "passive"))
    (pad "2" smd roundrect (at 0.485 0 180) (size 0.59 0.64) (layers "B.Cu" "B.Paste" "B.Mask") (roundrect_rratio 0.25)
      (net 431 "Net-(Q19-C)") (pintype "passive"))
  )
	(footprint "kria-k26-devboard-footprints:Fiducial_1mm_Mask2mm" (layer "B.Cu")
    (at 183.3 55.4 180)
    (descr "Circular Fiducial, 1mm bare copper, 3mm soldermask opening")
    (tags "fiducial")
    (attr smd board_only exclude_from_bom)
    (fp_text reference "FID6" (at -0.07 -3.21 90) (layer "B.SilkS")
        (effects (font (size 1 1) (thickness 0.15)) (justify mirror))
    )
    (fp_text value "Fiducial_1mm_Mask2mm" (at 0 -2.6035) (layer "B.Fab") hide
        (effects (font (size 1 1) (thickness 0.15)) (justify mirror))
    )
    (fp_text user "License: Apache-2.0" (at -1.25 -7.003) (layer "B.Fab") hide
        (effects (font (size 0.7 0.7) (thickness 0.15)) (justify left bottom mirror))
    )
    (fp_text user "${REFERENCE}" (at 0 0) (layer "B.Fab")
        (effects (font (size 0.4 0.4) (thickness 0.06)) (justify mirror))
    )
    (fp_text user "Author: Antmicro" (at -1.25 -5.803) (layer "B.Fab") hide
        (effects (font (size 0.7 0.7) (thickness 0.15)) (justify left bottom mirror))
    )
    (fp_circle (center 0 0) (end 1.24 0)
      (stroke (width 0.05) (type solid)) (fill none) (layer "B.CrtYd"))
    (fp_circle (center 0 0) (end 0.999 0)
      (stroke (width 0.15) (type solid)) (fill none) (layer "B.Fab"))
    (pad "" smd circle (at 0 0 180) (size 1 1) (layers "B.Cu" "B.Mask")
      (solder_mask_margin 0.5) (clearance 0.5))
  )
	(footprint "kria-k26-devboard-footprints:R_0603_1608Metric" (layer "B.Cu")
    (at 149.86 79.07 180)
    (descr "Resistor SMD 0603")
    (tags "resistor SMD 0603")
    (property "Author" "Antmicro")
    (property "License" "Apache-2.0")
    (property "MPN" "PMR03EZPJ000")
    (property "Manufacturer" "ROHM Semiconductor")
    (property "Max. Curr." "22.4A")
    (property "Sheetfile" "dc-dc-conventers.kicad_sch")
    (property "Sheetname" "DC/DC conventers")
    (property "Val" "0R")
    (property "ki_description" "Metal strip 0Ohm jumper 22.4A")
    (property "ki_keywords" "Metal strip 0Ohm jumper 22.4A high power hpwr current")
    (attr smd)
    (fp_text reference "R160" (at -1.57 -1.55) (layer "B.SilkS")
        (effects (font (size 0.7 0.7) (thickness 0.15)) (justify left bottom mirror))
    )
    (fp_text value "R_0R_22.4A_0603" (at 0 -1.6) (layer "B.Fab") hide
        (effects (font (size 0.7 0.7) (thickness 0.15)) (justify left bottom mirror))
    )
    (fp_text user "Author: Antmicro" (at -1.25 -4.9) (layer "B.Fab") hide
        (effects (font (size 0.7 0.7) (thickness 0.15)) (justify left bottom mirror))
    )
    (fp_text user "License: Apache-2.0" (at -1.25 -5.9) (layer "B.Fab") hide
        (effects (font (size 0.7 0.7) (thickness 0.15)) (justify left bottom mirror))
    )
    (fp_text user "${REFERENCE}" (at -1.25 -3.898) (layer "B.Fab") hide
        (effects (font (size 0.7 0.7) (thickness 0.15)) (justify left bottom mirror))
    )
    (fp_line (start -0.3 -0.3) (end 0.3 -0.3)
      (stroke (width 0.15) (type solid)) (layer "B.SilkS"))
    (fp_line (start -0.3 0.3) (end 0.3 0.3)
      (stroke (width 0.15) (type solid)) (layer "B.SilkS"))
    (fp_rect (start -1.25 0.7) (end 1.25 -0.7)
      (stroke (width 0.05) (type solid)) (fill none) (layer "B.CrtYd"))
    (fp_rect (start -0.8 0.4) (end 0.8 -0.4)
      (stroke (width 0.15) (type solid)) (fill none) (layer "B.Fab"))
    (pad "1" smd roundrect (at -0.7 0 180) (size 0.6 0.8) (layers "B.Cu" "B.Paste" "B.Mask") (roundrect_rratio 0.2)
      (net 772 "/Power Supply/DC/DC conventers/USB_5V_OUT") (pintype "passive"))
    (pad "2" smd roundrect (at 0.7 0 180) (size 0.6 0.8) (layers "B.Cu" "B.Paste" "B.Mask") (roundrect_rratio 0.2)
      (net 306 "USB_5V") (pintype "passive"))
  )
)
